# S9S_MB_2U (Grand Teton) — schematic netlist excerpt (pin names and nets, part order shuffled) for the footprints in the layout excerpt that follows; sources: Cadence DE-HDL packaged netlist, KiCad conversion of 03242023_DA0F0TMBIJ0_F0T_Motherboard_J_brd_V01_OCP.brd

J22  SCONN288_ADR50017P087CC  SCONN288_ADR50017-P087CC IO  pkg DDR288S_1-1VXB  page 103
  VIN_BULK0  = P12V_S3_AUX_CPU1_NVDIMM
  RFU0  = TP_CHC_CPU1_DIMM2_FRU_0
  VIN_MGMT  = P3V3_AUX
  HSCL  = I3C_SPD_DDRABCD_CPU1_LVC1_SCL_5
  HSDA  = I3C_SPD_DDRABCD_CPU1_LVC1_SDA
  VSS0  = GND
  DQ0_A  = M_C_CPU1_SA_DQ<0>
  VSS1  = GND
  DQ1_A  = M_C_CPU1_SA_DQ<1>
  VSS2  = GND
  DQS0_A_T  = M_C_CPU1_SA_DQS_DP<0>
  DQS0_A_C  = M_C_CPU1_SA_DQS_DN<0>
  VSS3  = GND
  DQ4_A  = M_C_CPU1_SA_DQ<4>
  VSS4  = GND
  DQ5_A  = M_C_CPU1_SA_DQ<5>
  VSS5  = GND
  DQ8_A  = M_C_CPU1_SA_DQ<8>
  VSS6  = GND
  DQ9_A  = M_C_CPU1_SA_DQ<9>
  VSS7  = GND
  DQS1_A_T  = M_C_CPU1_SA_DQS_DP<1>
  DQS1_A_C  = M_C_CPU1_SA_DQS_DN<1>
  VSS8  = GND
  DQ12_A  = M_C_CPU1_SA_DQ<12>
  VSS9  = GND
  DQ13_A  = M_C_CPU1_SA_DQ<13>
  VSS10  = GND
  DQ16_A  = M_C_CPU1_SA_DQ<16>
  VSS11  = GND
  DQ17_A  = M_C_CPU1_SA_DQ<17>
  VSS12  = GND
  DQS2_A_T  = M_C_CPU1_SA_DQS_DP<2>
  DQS2_A_C  = M_C_CPU1_SA_DQS_DN<2>
  VSS13  = GND
  DQ20_A  = M_C_CPU1_SA_DQ<20>
  VSS14  = GND
  DQ21_A  = M_C_CPU1_SA_DQ<21>
  VSS15  = GND
  DQ24_A  = M_C_CPU1_SA_DQ<24>
  VSS16  = GND
  DQ25_A  = M_C_CPU1_SA_DQ<25>
  VSS17  = GND
  DQS3_A_T  = M_C_CPU1_SA_DQS_DP<3>
  DQS3_A_C  = M_C_CPU1_SA_DQS_DN<3>
  VSS18  = GND
  DQ28_A  = M_C_CPU1_SA_DQ<28>
  VSS19  = GND
  DQ29_A  = M_C_CPU1_SA_DQ<29>
  VSS20  = GND
  CB0_A  = M_C_CPU1_SA_CB<0>
  VSS21  = GND
  CB1_A  = M_C_CPU1_SA_CB<1>
  VSS22  = GND
  DQS4_A_T  = M_C_CPU1_SA_DQS_DP<4>
  DQS4_A_C  = M_C_CPU1_SA_DQS_DN<4>
  VSS23  = GND
  CB4_A  = M_C_CPU1_SA_CB<4>
  VSS24  = GND
  CB5_A  = M_C_CPU1_SA_CB<5>
  VSS25  = GND
  ALERT_N  = M_C_CPU1_ALERT_N
  VSS26  = GND
  CS0_A_N  = M_C_CPU1_SA_CS_N<2>
  VSS27  = GND
  CA0_A  = M_C_CPU1_SA_CA<0>
  VSS28  = GND
  CA2_A  = M_C_CPU1_SA_CA<2>
  VSS29  = GND
  CA4_A  = M_C_CPU1_SA_CA<4>
  VSS30  = GND
  CA6_A  = M_C_CPU1_SA_CA<6>
  VSS31  = GND
  PAR_A  = M_C_CPU1_SA_PAR
  VSS32  = GND
  CA0_B  = M_C_CPU1_SB_CA<0>
  VSS33  = GND
  CA2_B  = M_C_CPU1_SB_CA<2>
  VSS34  = GND
  CA4_B  = M_C_CPU1_SB_CA<4>
  VSS35  = GND
  CA6_B  = M_C_CPU1_SB_CA<6>
  VSS36  = GND
  CS0_B_N  = M_C_CPU1_SB_CS_N<2>
  VSS37  = GND
  \lbd||rsp_a_n\  = M_C_CPU1_SA_RSP<1>
  \lbs||rsp_b_n\  = M_C_CPU1_SB_RSP<1>
  VSS38  = GND
  CB4_B  = M_C_CPU1_SB_CB<4>
  VSS39  = GND
  CB5_B  = M_C_CPU1_SB_CB<5>
  VSS40  = GND
  \dqs9_b_t||tdqs9_b_t||dbi4_b_n\  = M_C_CPU1_SB_DQS_DP<9>
  \dqs9_b_c||tdqs9_b_c\  = M_C_CPU1_SB_DQS_DN<9>
  VSS41  = GND
  CB0_B  = M_C_CPU1_SB_CB<0>
  VSS42  = GND
  CB1_B  = M_C_CPU1_SB_CB<1>
  VSS43  = GND
  DQ0_B  = M_C_CPU1_SB_DQ<0>
  VSS44  = GND
  DQ1_B  = M_C_CPU1_SB_DQ<1>
  VSS45  = GND
  DQS0_B_T  = M_C_CPU1_SB_DQS_DP<0>
  DQS0_B_C  = M_C_CPU1_SB_DQS_DN<0>
  VSS46  = GND
  DQ4_B  = M_C_CPU1_SB_DQ<4>
  VSS47  = GND
  DQ5_B  = M_C_CPU1_SB_DQ<5>
  VSS48  = GND
  DQ8_B  = M_C_CPU1_SB_DQ<8>
  VSS49  = GND
  DQ9_B  = M_C_CPU1_SB_DQ<9>
  VSS50  = GND
  DQS1_B_T  = M_C_CPU1_SB_DQS_DP<1>
  DQS1_B_C  = M_C_CPU1_SB_DQS_DN<1>
  VSS51  = GND
  DQ12_B  = M_C_CPU1_SB_DQ<12>
  VSS52  = GND
  DQ13_B  = M_C_CPU1_SB_DQ<13>
  VSS53  = GND
  DQ16_B  = M_C_CPU1_SB_DQ<16>
  VSS54  = GND
  DQ17_B  = M_C_CPU1_SB_DQ<17>
  VSS55  = GND
  DQS2_B_T  = M_C_CPU1_SB_DQS_DP<2>
  DQS2_B_C  = M_C_CPU1_SB_DQS_DN<2>
  VSS56  = GND
  DQ20_B  = M_C_CPU1_SB_DQ<20>
  VSS57  = GND
  DQ21_B  = M_C_CPU1_SB_DQ<21>
  VSS58  = GND
  DQ24_B  = M_C_CPU1_SB_DQ<24>
  VSS59  = GND
  DQ25_B  = M_C_CPU1_SB_DQ<25>
  VSS60  = GND
  DQS3_B_T  = M_C_CPU1_SB_DQS_DP<3>
  DQS3_B_C  = M_C_CPU1_SB_DQS_DN<3>
  VSS61  = GND
  DQ28_B  = M_C_CPU1_SB_DQ<28>
  VSS62  = GND
  DQ29_B  = M_C_CPU1_SB_DQ<29>
  VSS63  = GND
  RFU1  = TP_CHC_CPU1_DIMM2_FRU_1
  VIN_BULK1  = P12V_S3_AUX_CPU1_NVDIMM
  VIN_BULK2  = P12V_S3_AUX_CPU1_NVDIMM
  \pwr_good||fail_n\  = PWRGD_CHC_CPU1_DIMM2
  HSA  = PD_CHC_CPU1_DIMM2_SAA
  RFU2  = TP_CHC_CPU1_DIMM2_FRU_2
  RFU3  = TP_CHC_CPU1_DIMM2_FRU_3
  VSS64  = GND
  DQ2_A  = M_C_CPU1_SA_DQ<2>
  VSS65  = GND
  DQ3_A  = M_C_CPU1_SA_DQ<3>
  VSS66  = GND
  \dqs5_a_c||tdqs5_a_c||dqs5_a_t||tdqs5_a_t\  = M_C_CPU1_SA_DQS_DN<5>
  \dqs5_a_t||tdqs5_a_t\  = M_C_CPU1_SA_DQS_DP<5>
  VSS67  = GND
  DQ6_A  = M_C_CPU1_SA_DQ<6>
  VSS68  = GND
  DQ7_A  = M_C_CPU1_SA_DQ<7>
  VSS69  = GND
  DQ10_A  = M_C_CPU1_SA_DQ<10>
  VSS70  = GND
  DQ11_A  = M_C_CPU1_SA_DQ<11>
  VSS71  = GND
  \dqs6_a_c||tdqs6_a_c||dqs6_a_t||tdqs6_a_t\  = M_C_CPU1_SA_DQS_DN<6>
  \dqs6_a_t||tdqs6_a_t\  = M_C_CPU1_SA_DQS_DP<6>
  VSS72  = GND
  DQ14_A  = M_C_CPU1_SA_DQ<14>
  VSS73  = GND
  DQ15_A  = M_C_CPU1_SA_DQ<15>
  VSS74  = GND
  DQ18_A  = M_C_CPU1_SA_DQ<18>
  VSS75  = GND
  DQ19_A  = M_C_CPU1_SA_DQ<19>
  VSS76  = GND
  \dqs7_a_c||tdqs7_a_c\  = M_C_CPU1_SA_DQS_DN<7>
  \dqs7_a_t||tdqs7_a_t\  = M_C_CPU1_SA_DQS_DP<7>
  VSS77  = GND
  DQ22_A  = M_C_CPU1_SA_DQ<22>
  VSS78  = GND
  DQ23_A  = M_C_CPU1_SA_DQ<23>
  VSS79  = GND
  DQ26_A  = M_C_CPU1_SA_DQ<26>
  VSS80  = GND
  DQ27_A  = M_C_CPU1_SA_DQ<27>
  VSS81  = GND
  \dqs8_a_c||tdqs8_a_c\  = M_C_CPU1_SA_DQS_DN<8>
  \dqs8_a_t||tdqs8_a_t\  = M_C_CPU1_SA_DQS_DP<8>
  VSS82  = GND
  DQ30_A  = M_C_CPU1_SA_DQ<30>
  VSS83  = GND
  DQ31_A  = M_C_CPU1_SA_DQ<31>
  VSS84  = GND
  CB2_A  = M_C_CPU1_SA_CB<2>
  VSS85  = GND
  CB3_A  = M_C_CPU1_SA_CB<3>
  VSS86  = GND
  \dqs9_a_c||tdqs9_a_c\  = M_C_CPU1_SA_DQS_DN<9>
  \dqs9_a_t||tdqs9_a_t\  = M_C_CPU1_SA_DQS_DP<9>
  VSS87  = GND
  CB6_A  = M_C_CPU1_SA_CB<6>
  VSS88  = GND
  CB7_A  = M_C_CPU1_SA_CB<7>
  VSS89  = GND
  RESET_N  = RST_M_CD_CPU1_FPGA_N
  VSS90  = GND
  CS1_A_N  = M_C_CPU1_SA_CS_N<3>
  VSS91  = GND
  CA1_A  = M_C_CPU1_SA_CA<1>
  VSS92  = GND
  CA3_A  = M_C_CPU1_SA_CA<3>
  VSS93  = GND
  CA5_A  = M_C_CPU1_SA_CA<5>
  VSS94  = GND
  CK_T  = M_C_CPU1_CLK_DP<1>
  CK_C  = M_C_CPU1_CLK_DN<1>
  VSS95  = GND
  RFU4  = TP_CHC_CPU1_DIMM2_FRU_4
  CA1_B  = M_C_CPU1_SB_CA<1>
  VSS96  = GND
  CA3_B  = M_C_CPU1_SB_CA<3>
  VSS97  = GND
  CA5_B  = M_C_CPU1_SB_CA<5>
  VSS98  = GND
  PAR_B  = M_C_CPU1_SB_PAR
  VSS99  = GND
  CS1_B_N  = M_C_CPU1_SB_CS_N<3>
  VSS100  = GND
  RFU5  = TP_CHC_CPU1_DIMM2_FRU_5
  RFU6  = TP_CHC_CPU1_DIMM2_FRU_6
  VSS101  = GND
  CB6_B  = M_C_CPU1_SB_CB<6>
  VSS102  = GND
  CB7_B  = M_C_CPU1_SB_CB<7>
  VSS103  = GND
  DQS4_B_C  = M_C_CPU1_SB_DQS_DN<4>
  DQS4_B_T  = M_C_CPU1_SB_DQS_DP<4>
  VSS104  = GND
  CB2_B  = M_C_CPU1_SB_CB<2>
  VSS105  = GND
  CB3_B  = M_C_CPU1_SB_CB<3>
  VSS106  = GND
  DQ2_B  = M_C_CPU1_SB_DQ<2>
  VSS107  = GND
  DQ3_B  = M_C_CPU1_SB_DQ<3>
  VSS108  = GND
  \dqs5_b_c||tdqs5_b_c\  = M_C_CPU1_SB_DQS_DN<5>
  \dqs5_b_t||tdqs5_b_t\  = M_C_CPU1_SB_DQS_DP<5>
  VSS109  = GND
  DQ6_B  = M_C_CPU1_SB_DQ<6>
  VSS110  = GND
  DQ7_B  = M_C_CPU1_SB_DQ<7>
  VSS111  = GND
  DQ10_B  = M_C_CPU1_SB_DQ<10>
  VSS112  = GND
  DQ11_B  = M_C_CPU1_SB_DQ<11>
  VSS113  = GND
  \dqs6_b_c||tdqs6_b_c\  = M_C_CPU1_SB_DQS_DN<6>
  \dqs6_b_t||tdqs6_b_t\  = M_C_CPU1_SB_DQS_DP<6>
  VSS114  = GND
  DQ14_B  = M_C_CPU1_SB_DQ<14>
  VSS115  = GND
  DQ15_B  = M_C_CPU1_SB_DQ<15>
  VSS116  = GND
  DQ18_B  = M_C_CPU1_SB_DQ<18>
  VSS117  = GND
  DQ19_B  = M_C_CPU1_SB_DQ<19>
  VSS118  = GND
  \dqs7_b_c||tdqs7_b_c\  = M_C_CPU1_SB_DQS_DN<7>
  \dqs7_b_t||tdqs7_b_t\  = M_C_CPU1_SB_DQS_DP<7>
  VSS119  = GND
  DQ22_B  = M_C_CPU1_SB_DQ<22>
  VSS120  = GND
  DQ23_B  = M_C_CPU1_SB_DQ<23>
  VSS121  = GND
  DQ26_B  = M_C_CPU1_SB_DQ<26>
  VSS122  = GND
  DQ27_B  = M_C_CPU1_SB_DQ<27>
  VSS123  = GND
  \dqs8_b_c||tdqs8_b_c\  = M_C_CPU1_SB_DQS_DN<8>
  \dqs8_b_t||tdqs8_b_t\  = M_C_CPU1_SB_DQS_DP<8>
  VSS124  = GND
  DQ30_B  = M_C_CPU1_SB_DQ<30>
  VSS125  = GND
  DQ31_B  = M_C_CPU1_SB_DQ<31>
  VSS126  = GND
  G1  = GND
  G2  = GND
  G3  = GND

(kicad_pcb
	(version 20260206)
	(generator "pcbnew")
	(generator_version "10.0")
	(general
		(thickness 1.6)
		(legacy_teardrops no)
	)
	(paper "A4")
	(title_block
		(title "03242023_DA0F0TMBIJ0_F0T_Motherboard_J_brd_V01_OCP.brd")
		(comment 1 "Grand Teton / footprint 501 of 6105 (J22), pads 275-291 of 291")
	)
	(layers
		(0 "F.Cu" signal "TOP")
		(4 "In1.Cu" signal "GND")
		(6 "In2.Cu" signal "IN1")
		(8 "In3.Cu" signal "GND1")
		(10 "In4.Cu" signal "IN2")
		(12 "In5.Cu" signal "GND2")
		(14 "In6.Cu" signal "IN3")
		(16 "In7.Cu" signal "GND3")
		(18 "In8.Cu" signal "VCC")
		(20 "In9.Cu" signal "VCC1")
		(22 "In10.Cu" signal "GND4")
		(24 "In11.Cu" signal "IN4")
		(26 "In12.Cu" signal "GND5")
		(28 "In13.Cu" signal "IN5")
		(30 "In14.Cu" signal "GND6")
		(32 "In15.Cu" signal "IN6")
		(34 "In16.Cu" signal "GND7")
		(2 "B.Cu" signal "BOTTOM")
		(9 "F.Adhes" user "F.Adhesive")
		(11 "B.Adhes" user "B.Adhesive")
		(13 "F.Paste" user "Package Geometry/Pastemask Top")
		(15 "B.Paste" user "Package Geometry/Pastemask Bottom")
		(5 "F.SilkS" user "Ref Des/Silkscreen Top")
		(7 "B.SilkS" user "Ref Des/Silkscreen Bottom")
		(1 "F.Mask" user "Board Geometry/Soldermask Top")
		(3 "B.Mask" user "Board Geometry/Soldermask Bottom")
		(17 "Dwgs.User" user "User.Drawings")
		(19 "Cmts.User" user "User.Comments")
		(21 "Eco1.User" user "User.Eco1")
		(23 "Eco2.User" user "User.Eco2")
		(25 "Edge.Cuts" user "Board Geometry/Outline")
		(27 "Margin" user)
		(31 "F.CrtYd" user "Package Geometry/Place Bound Top")
		(29 "B.CrtYd" user "Package Geometry/Place Bound Bottom")
		(35 "F.Fab" user "Ref Des/Assembly Top")
		(33 "B.Fab" user "Ref Des/Assembly Bottom")
	)
	(footprint ""
		(layer "F.Cu")
		(at 32.82188 -258.091686)
		(property "Reference" "J22"
			(at -1.420622 -81.912714 0)
			(unlocked yes)
			(layer "F.SilkS")
			(effects
				(font
					(size 0.7874 0.5842)
					(thickness 0.1524)
				)
				(justify left)
			)
		)
		(property "Value" ""
			(at 0 0 0)
			(layer "F.Fab")
			(effects
				(font
					(size 1.27 1.27)
				)
			)
		)
		(duplicate_pad_numbers_are_jumpers no)
		(pad "275" smd rect
			(at 2.050034 52.274978 270)
			(size 0.519938 1.4986)
			(layers "F.Cu" "F.Mask" "F.Paste")
			(net "GND")
		)
		(pad "276" smd rect
			(at 2.050034 53.125116 270)
			(size 0.519938 1.4986)
			(layers "F.Cu" "F.Mask" "F.Paste")
			(net "M_C_CPU1_SB_DQ<23>")
		)
		(pad "277" smd rect
			(at 2.050034 53.975 270)
			(size 0.519938 1.4986)
			(layers "F.Cu" "F.Mask" "F.Paste")
			(net "GND")
		)
		(pad "278" smd rect
			(at 2.050034 54.824884 270)
			(size 0.519938 1.4986)
			(layers "F.Cu" "F.Mask" "F.Paste")
			(net "M_C_CPU1_SB_DQ<26>")
		)
		(pad "279" smd rect
			(at 2.050034 55.675022 270)
			(size 0.519938 1.4986)
			(layers "F.Cu" "F.Mask" "F.Paste")
			(net "GND")
		)
		(pad "280" smd rect
			(at 2.050034 56.524906 270)
			(size 0.519938 1.4986)
			(layers "F.Cu" "F.Mask" "F.Paste")
			(net "M_C_CPU1_SB_DQ<27>")
		)
		(pad "281" smd rect
			(at 2.050034 57.375044 270)
			(size 0.519938 1.4986)
			(layers "F.Cu" "F.Mask" "F.Paste")
			(net "GND")
		)
		(pad "282" smd rect
			(at 2.050034 58.224928 270)
			(size 0.519938 1.4986)
			(layers "F.Cu" "F.Mask" "F.Paste")
			(net "M_C_CPU1_SB_DQS_DN<8>")
		)
		(pad "283" smd rect
			(at 2.050034 59.075066 270)
			(size 0.519938 1.4986)
			(layers "F.Cu" "F.Mask" "F.Paste")
			(net "M_C_CPU1_SB_DQS_DP<8>")
		)
		(pad "284" smd rect
			(at 2.050034 59.92495 270)
			(size 0.519938 1.4986)
			(layers "F.Cu" "F.Mask" "F.Paste")
			(net "GND")
		)
		(pad "285" smd rect
			(at 2.050034 60.775088 270)
			(size 0.519938 1.4986)
			(layers "F.Cu" "F.Mask" "F.Paste")
			(net "M_C_CPU1_SB_DQ<30>")
		)
		(pad "286" smd rect
			(at 2.050034 61.624972 270)
			(size 0.519938 1.4986)
			(layers "F.Cu" "F.Mask" "F.Paste")
			(net "GND")
		)
		(pad "287" smd rect
			(at 2.050034 62.47511 270)
			(size 0.519938 1.4986)
			(layers "F.Cu" "F.Mask" "F.Paste")
			(net "M_C_CPU1_SB_DQ<31>")
		)
		(pad "288" smd rect
			(at 2.050034 63.324994 270)
			(size 0.519938 1.4986)
			(layers "F.Cu" "F.Mask" "F.Paste")
			(net "GND")
		)
		(pad "G1" thru_hole oval
			(at 0 -68.97497)
			(size 2.8194 1.5748)
			(drill oval 2.4384 1.1938)
			(layers "*.Cu" "*.Mask")
			(remove_unused_layers no)
			(net "GND")
			(clearance 0.127)
			(thermal_gap 0.127)
		)
		(pad "G2" thru_hole oval
			(at 0 3.875024)
			(size 2.8194 1.5748)
			(drill oval 2.4384 1.1938)
			(layers "*.Cu" "*.Mask")
			(remove_unused_layers no)
			(net "GND")
			(clearance 0.127)
			(thermal_gap 0.127)
		)
		(pad "G3" thru_hole oval
			(at 0 68.97497)
			(size 2.8194 1.5748)
			(drill oval 2.4384 1.1938)
			(layers "*.Cu" "*.Mask")
			(remove_unused_layers no)
			(net "GND")
			(clearance 0.127)
			(thermal_gap 0.127)
		)
	)
)
